# T6G (Grand Teton) — schematic netlist excerpt (pin names and nets, part order shuffled) for the footprints in the layout excerpt that follows; sources: Cadence DE-HDL packaged netlist, KiCad conversion of 04192023_DAF0TMB3IC0_F0TG_MB_C_brd_V02_OCP.brd

C766  Q_CAP_DIFFBUS  DIFF BUS_0.22UF 6.3V 20% X6S  pkg C0201  page 66 : \1\ = P5E_CPU1_P2_TX_C_DN<3> ; \2\ = P5E_CPU1_P2_TX_DN<3>
PC433  Q_CAP  2.2UF 10V 10% X6S  pkg C0402  page 222 : A = PVDDIO_P1_VCC1 ; B = GND
R3277  Q_RES  1K 1% EMPTY  pkg 0402LF  page 111 : A = P3V3_AUX ; B = FM_P2E_EQA0

(kicad_pcb
	(version 20260206)
	(generator "pcbnew")
	(generator_version "10.0")
	(general
		(thickness 1.6)
		(legacy_teardrops no)
	)
	(paper "A4")
	(title_block
		(title "04192023_DAF0TMB3IC0_F0TG_MB_C_brd_V02_OCP.brd")
		(comment 1 "Grand Teton / footprints 2398-2400 of 8354")
	)
	(layers
		(0 "F.Cu" signal "TOP")
		(4 "In1.Cu" signal "GND")
		(6 "In2.Cu" signal "IN1")
		(8 "In3.Cu" signal "GND1")
		(10 "In4.Cu" signal "IN2")
		(12 "In5.Cu" signal "GND2")
		(14 "In6.Cu" signal "IN3")
		(16 "In7.Cu" signal "GND3")
		(18 "In8.Cu" signal "VCC")
		(20 "In9.Cu" signal "VCC1")
		(22 "In10.Cu" signal "GND4")
		(24 "In11.Cu" signal "IN4")
		(26 "In12.Cu" signal "GND5")
		(28 "In13.Cu" signal "IN5")
		(30 "In14.Cu" signal "GND6")
		(32 "In15.Cu" signal "IN6")
		(34 "In16.Cu" signal "GND7")
		(2 "B.Cu" signal "BOTTOM")
		(9 "F.Adhes" user "F.Adhesive")
		(11 "B.Adhes" user "B.Adhesive")
		(13 "F.Paste" user "Package Geometry/Pastemask Top")
		(15 "B.Paste" user "Package Geometry/Pastemask Bottom")
		(5 "F.SilkS" user "Ref Des/Silkscreen Top")
		(7 "B.SilkS" user "Ref Des/Silkscreen Bottom")
		(1 "F.Mask" user "Board Geometry/Soldermask Top")
		(3 "B.Mask" user "Board Geometry/Soldermask Bottom")
		(17 "Dwgs.User" user "User.Drawings")
		(19 "Cmts.User" user "User.Comments")
		(21 "Eco1.User" user "User.Eco1")
		(23 "Eco2.User" user "User.Eco2")
		(25 "Edge.Cuts" user "Board Geometry/Outline")
		(27 "Margin" user)
		(31 "F.CrtYd" user "Package Geometry/Place Bound Top")
		(29 "B.CrtYd" user "Package Geometry/Place Bound Bottom")
		(35 "F.Fab" user "Ref Des/Assembly Top")
		(33 "B.Fab" user "Ref Des/Assembly Bottom")
	)
	(footprint ""
		(layer "F.Cu")
		(at 49.860454 -349.386398 90)
		(property "Reference" "PC433"
			(at 0 0 90)
			(layer "F.SilkS")
			(hide yes)
			(effects
				(font
					(size 1.27 1.27)
				)
			)
		)
		(property "Value" ""
			(at 0 0 90)
			(layer "F.Fab")
			(effects
				(font
					(size 1.27 1.27)
				)
			)
		)
		(duplicate_pad_numbers_are_jumpers no)
		(fp_line
			(start 0.7874 -0.4064)
			(end 0.7874 0.4064)
			(stroke
				(width 0.1524)
				(type default)
			)
			(layer "F.SilkS")
		)
		(fp_line
			(start -0.7874 -0.4064)
			(end 0.7874 -0.4064)
			(stroke
				(width 0.1524)
				(type default)
			)
			(layer "F.SilkS")
		)
		(fp_line
			(start 0.7874 0.4064)
			(end 0.447802 0.4064)
			(stroke
				(width 0.1524)
				(type default)
			)
			(layer "F.SilkS")
		)
		(fp_line
			(start -0.263398 0.4064)
			(end -0.7874 0.4064)
			(stroke
				(width 0.1524)
				(type default)
			)
			(layer "F.SilkS")
		)
		(fp_line
			(start -0.7874 0.4064)
			(end -0.7874 -0.4064)
			(stroke
				(width 0.1524)
				(type default)
			)
			(layer "F.SilkS")
		)
		(fp_line
			(start -0.12065 -0.305054)
			(end -0.12065 -0.2794)
			(stroke
				(width 0.1)
				(type default)
			)
			(layer "F.Fab")
		)
		(fp_line
			(start -0.67945 -0.305054)
			(end -0.12065 -0.305054)
			(stroke
				(width 0.1)
				(type default)
			)
			(layer "F.Fab")
		)
		(fp_line
			(start 0.67945 -0.3048)
			(end 0.67945 0.3048)
			(stroke
				(width 0.1)
				(type default)
			)
			(layer "F.Fab")
		)
		(fp_line
			(start 0.12065 -0.3048)
			(end 0.67945 -0.3048)
			(stroke
				(width 0.1)
				(type default)
			)
			(layer "F.Fab")
		)
		(fp_line
			(start 0.12065 -0.2794)
			(end 0.12065 -0.3048)
			(stroke
				(width 0.1)
				(type default)
			)
			(layer "F.Fab")
		)
		(fp_line
			(start -0.12065 -0.2794)
			(end 0.12065 -0.2794)
			(stroke
				(width 0.1)
				(type default)
			)
			(layer "F.Fab")
		)
		(fp_line
			(start 0.120396 0.2794)
			(end -0.12065 0.2794)
			(stroke
				(width 0.1)
				(type default)
			)
			(layer "F.Fab")
		)
		(fp_line
			(start -0.12065 0.2794)
			(end -0.12065 0.3048)
			(stroke
				(width 0.1)
				(type default)
			)
			(layer "F.Fab")
		)
		(fp_line
			(start 0.67945 0.3048)
			(end 0.120396 0.3048)
			(stroke
				(width 0.1)
				(type default)
			)
			(layer "F.Fab")
		)
		(fp_line
			(start 0.120396 0.3048)
			(end 0.120396 0.2794)
			(stroke
				(width 0.1)
				(type default)
			)
			(layer "F.Fab")
		)
		(fp_line
			(start -0.12065 0.3048)
			(end -0.67945 0.3048)
			(stroke
				(width 0.1)
				(type default)
			)
			(layer "F.Fab")
		)
		(fp_line
			(start -0.67945 0.3048)
			(end -0.67945 -0.305054)
			(stroke
				(width 0.1)
				(type default)
			)
			(layer "F.Fab")
		)
		(pad "1" smd circle
			(at -0.40005 0 90)
			(size 0 0)
			(layers "F.Cu" "F.Mask" "F.Paste")
			(net "PVDDIO_P1_VCC1")
		)
		(pad "2" smd circle
			(at 0.40005 0 90)
			(size 0 0)
			(layers "F.Cu" "F.Mask" "F.Paste")
			(net "GND")
		)
	)
	(footprint ""
		(layer "F.Cu")
		(at 145.233644 -370.57203 -90)
		(property "Reference" "C766"
			(at 0 0 270)
			(layer "F.SilkS")
			(hide yes)
			(effects
				(font
					(size 1.27 1.27)
				)
			)
		)
		(property "Value" ""
			(at 0 0 270)
			(layer "F.Fab")
			(effects
				(font
					(size 1.27 1.27)
				)
			)
		)
		(duplicate_pad_numbers_are_jumpers no)
		(fp_line
			(start -0.299974 0.150114)
			(end -0.299974 -0.150114)
			(stroke
				(width 0.1)
				(type default)
			)
			(layer "F.Fab")
		)
		(fp_line
			(start 0.299974 0.150114)
			(end -0.299974 0.150114)
			(stroke
				(width 0.1)
				(type default)
			)
			(layer "F.Fab")
		)
		(fp_line
			(start -0.299974 -0.150114)
			(end 0.299974 -0.150114)
			(stroke
				(width 0.1)
				(type default)
			)
			(layer "F.Fab")
		)
		(fp_line
			(start 0.299974 -0.150114)
			(end 0.299974 0.150114)
			(stroke
				(width 0.1)
				(type default)
			)
			(layer "F.Fab")
		)
		(pad "1" smd rect
			(at -0.2667 0 270)
			(size 0.3048 0.381)
			(layers "F.Cu" "F.Mask" "F.Paste")
			(net "P5E_CPU1_P2_TX_C_DN<3>")
		)
		(pad "2" smd rect
			(at 0.2667 0 270)
			(size 0.3048 0.381)
			(layers "F.Cu" "F.Mask" "F.Paste")
			(net "P5E_CPU1_P2_TX_DN<3>")
		)
	)
	(footprint ""
		(layer "F.Cu")
		(at 29.045662 -424.259502)
		(property "Reference" "R3277"
			(at 0 0 0)
			(layer "F.SilkS")
			(hide yes)
			(effects
				(font
					(size 1.27 1.27)
				)
			)
		)
		(property "Value" ""
			(at 0 0 0)
			(layer "F.Fab")
			(effects
				(font
					(size 1.27 1.27)
				)
			)
		)
		(duplicate_pad_numbers_are_jumpers no)
		(fp_line
			(start -0.7874 -0.4064)
			(end 0.7874 -0.4064)
			(stroke
				(width 0.1524)
				(type default)
			)
			(layer "F.SilkS")
		)
		(fp_line
			(start -0.7874 0.4064)
			(end -0.7874 -0.4064)
			(stroke
				(width 0.1524)
				(type default)
			)
			(layer "F.SilkS")
		)
		(fp_line
			(start 0.7874 -0.4064)
			(end 0.7874 0.4064)
			(stroke
				(width 0.1524)
				(type default)
			)
			(layer "F.SilkS")
		)
		(fp_line
			(start 0.7874 0.4064)
			(end -0.7874 0.4064)
			(stroke
				(width 0.1524)
				(type default)
			)
			(layer "F.SilkS")
		)
		(fp_line
			(start -0.67945 -0.305054)
			(end -0.12065 -0.305054)
			(stroke
				(width 0.1)
				(type default)
			)
			(layer "F.Fab")
		)
		(fp_line
			(start -0.67945 0.3048)
			(end -0.67945 -0.305054)
			(stroke
				(width 0.1)
				(type default)
			)
			(layer "F.Fab")
		)
		(fp_line
			(start -0.12065 -0.305054)
			(end -0.12065 -0.2794)
			(stroke
				(width 0.1)
				(type default)
			)
			(layer "F.Fab")
		)
		(fp_line
			(start -0.12065 -0.2794)
			(end 0.12065 -0.2794)
			(stroke
				(width 0.1)
				(type default)
			)
			(layer "F.Fab")
		)
		(fp_line
			(start -0.12065 0.2794)
			(end -0.12065 0.3048)
			(stroke
				(width 0.1)
				(type default)
			)
			(layer "F.Fab")
		)
		(fp_line
			(start -0.12065 0.3048)
			(end -0.67945 0.3048)
			(stroke
				(width 0.1)
				(type default)
			)
			(layer "F.Fab")
		)
		(fp_line
			(start 0.120396 0.2794)
			(end -0.12065 0.2794)
			(stroke
				(width 0.1)
				(type default)
			)
			(layer "F.Fab")
		)
		(fp_line
			(start 0.120396 0.3048)
			(end 0.120396 0.2794)
			(stroke
				(width 0.1)
				(type default)
			)
			(layer "F.Fab")
		)
		(fp_line
			(start 0.12065 -0.3048)
			(end 0.67945 -0.3048)
			(stroke
				(width 0.1)
				(type default)
			)
			(layer "F.Fab")
		)
		(fp_line
			(start 0.12065 -0.2794)
			(end 0.12065 -0.3048)
			(stroke
				(width 0.1)
				(type default)
			)
			(layer "F.Fab")
		)
		(fp_line
			(start 0.67945 -0.3048)
			(end 0.67945 0.3048)
			(stroke
				(width 0.1)
				(type default)
			)
			(layer "F.Fab")
		)
		(fp_line
			(start 0.67945 0.3048)
			(end 0.120396 0.3048)
			(stroke
				(width 0.1)
				(type default)
			)
			(layer "F.Fab")
		)
		(pad "1" smd circle
			(at -0.40005 0)
			(size 0 0)
			(layers "F.Cu" "F.Mask" "F.Paste")
			(net "P3V3_AUX")
		)
		(pad "2" smd circle
			(at 0.40005 0)
			(size 0 0)
			(layers "F.Cu" "F.Mask" "F.Paste")
			(net "FM_P2E_EQA0")
		)
	)
)
